(kicad_pcb
	(version 20260206)
	(generator "pcbnew")
	(generator_version "10.0")
	(general
		(thickness 1.6)
		(legacy_teardrops no)
	)
	(paper "A4")
	(title_block
		(title "Wiwynn_Tioga_Pass_MB.brd")
		(comment 1 "Tioga Pass / footprints 3434-3440 of 4770")
	)
	(layers
		(0 "F.Cu" signal "TOP")
		(4 "In1.Cu" signal "L2GND")
		(6 "In2.Cu" signal "L3")
		(8 "In3.Cu" signal "L4GND")
		(10 "In4.Cu" signal "L5")
		(12 "In5.Cu" signal "L6GND")
		(14 "In6.Cu" signal "L7VCC")
		(16 "In7.Cu" signal "L8VCC")
		(18 "In8.Cu" signal "L9GND")
		(20 "In9.Cu" signal "L10")
		(22 "In10.Cu" signal "L11GND")
		(24 "In11.Cu" signal "L12")
		(26 "In12.Cu" signal "L13GND")
		(2 "B.Cu" signal "BOTTOM")
		(9 "F.Adhes" user "F.Adhesive")
		(11 "B.Adhes" user "B.Adhesive")
		(13 "F.Paste" user "Package Geometry/Pastemask Top")
		(15 "B.Paste" user "Package Geometry/Pastemask Bottom")
		(5 "F.SilkS" user "Ref Des/Silkscreen Top")
		(7 "B.SilkS" user "Ref Des/Silkscreen Bottom")
		(1 "F.Mask" user "Board Geometry/Soldermask Top")
		(3 "B.Mask" user "Board Geometry/Soldermask Bottom")
		(17 "Dwgs.User" user "User.Drawings")
		(19 "Cmts.User" user "User.Comments")
		(21 "Eco1.User" user "User.Eco1")
		(23 "Eco2.User" user "User.Eco2")
		(25 "Edge.Cuts" user "Board Geometry/Outline")
		(27 "Margin" user)
		(31 "F.CrtYd" user "Package Geometry/Place Bound Top")
		(29 "B.CrtYd" user "Package Geometry/Place Bound Bottom")
		(35 "F.Fab" user "Ref Des/Assembly Top")
		(33 "B.Fab" user "Ref Des/Assembly Bottom")
	)
	(footprint ""
		(layer "B.Cu")
		(at -3.09626 -118.78056 180)
		(property "Reference" "C9M8"
			(at 0 0 0)
			(layer "B.SilkS")
			(hide yes)
			(effects
				(font
					(size 1.27 1.27)
				)
				(justify mirror)
			)
		)
		(property "Value" ""
			(at 0 0 0)
			(layer "B.Fab")
			(effects
				(font
					(size 1.27 1.27)
				)
				(justify mirror)
			)
		)
		(duplicate_pad_numbers_are_jumpers no)
		(fp_rect
			(start 0.3048 -0.1016)
			(end -0.3048 0.9906)
			(stroke
				(width 0)
				(type default)
			)
			(fill no)
			(layer "B.CrtYd")
		)
		(fp_line
			(start 0.3048 0.9906)
			(end -0.3048 0.9906)
			(stroke
				(width 0.1)
				(type default)
			)
			(layer "B.Fab")
		)
		(fp_line
			(start 0.3048 -0.1016)
			(end 0.3048 0.9906)
			(stroke
				(width 0.1)
				(type default)
			)
			(layer "B.Fab")
		)
		(fp_line
			(start -0.3048 0.9906)
			(end -0.3048 -0.1016)
			(stroke
				(width 0.1)
				(type default)
			)
			(layer "B.Fab")
		)
		(fp_line
			(start -0.3048 -0.1016)
			(end 0.3048 -0.1016)
			(stroke
				(width 0.1)
				(type default)
			)
			(layer "B.Fab")
		)
		(pad "1" smd rect
			(at 0 0)
			(size 0.508 0.508)
			(layers "B.Cu" "B.Mask" "B.Paste")
			(net "PVCCIO_CPU1")
		)
		(pad "2" smd rect
			(at 0 0.889)
			(size 0.508 0.508)
			(layers "B.Cu" "B.Mask" "B.Paste")
			(net "GND")
		)
		(zone
			(layer "B.Cu")
			(hatch none 0.5)
			(connect_pads
				(clearance 0)
			)
			(min_thickness 0.25)
			(keepout
				(tracks allowed)
				(vias not_allowed)
				(pads allowed)
				(copperpour not_allowed)
				(footprints allowed)
			)
			(placement
				(enabled no)
				(sheetname "")
			)
			(fill
				(thermal_gap 0.5)
				(thermal_bridge_width 0.5)
				(island_removal_mode 0)
			)
			(polygon
				(pts
					(xy -3.35026 -119.03456) (xy -2.84226 -119.03456) (xy -2.84226 -119.41556) (xy -3.35026 -119.41556)
				)
			)
		)
		(zone
			(layer "B.Cu")
			(hatch none 0.5)
			(connect_pads
				(clearance 0)
			)
			(min_thickness 0.25)
			(keepout
				(tracks not_allowed)
				(vias allowed)
				(pads allowed)
				(copperpour not_allowed)
				(footprints allowed)
			)
			(placement
				(enabled no)
				(sheetname "")
			)
			(fill
				(thermal_gap 0.5)
				(thermal_bridge_width 0.5)
				(island_removal_mode 0)
			)
			(polygon
				(pts
					(xy -3.35026 -119.03456) (xy -2.84226 -119.03456) (xy -2.84226 -119.41556) (xy -3.35026 -119.41556)
				)
			)
		)
	)
	(footprint ""
		(layer "B.Cu")
		(at 385.2545 -54.61 90)
		(property "Reference" "R1U6"
			(at 0 0 90)
			(layer "B.SilkS")
			(hide yes)
			(effects
				(font
					(size 1.27 1.27)
				)
				(justify mirror)
			)
		)
		(property "Value" ""
			(at 0 0 90)
			(layer "B.Fab")
			(effects
				(font
					(size 1.27 1.27)
				)
				(justify mirror)
			)
		)
		(duplicate_pad_numbers_are_jumpers no)
		(fp_poly
			(pts
				(xy 0.2794 -0.1016) (xy -0.2794 -0.1016) (xy -0.2794 0.9906) (xy 0.2794 0.9906)
			)
			(stroke
				(width 0)
				(type default)
			)
			(fill no)
			(layer "B.CrtYd")
		)
		(fp_line
			(start 0.2794 -0.1016)
			(end 0.2794 0.9906)
			(stroke
				(width 0.1)
				(type default)
			)
			(layer "B.Fab")
		)
		(fp_line
			(start -0.2794 -0.1016)
			(end 0.2794 -0.1016)
			(stroke
				(width 0.1)
				(type default)
			)
			(layer "B.Fab")
		)
		(fp_line
			(start 0.2794 0.9906)
			(end -0.2794 0.9906)
			(stroke
				(width 0.1)
				(type default)
			)
			(layer "B.Fab")
		)
		(fp_line
			(start -0.2794 0.9906)
			(end -0.2794 -0.1016)
			(stroke
				(width 0.1)
				(type default)
			)
			(layer "B.Fab")
		)
		(pad "1" smd rect
			(at 0 0 270)
			(size 0.508 0.508)
			(layers "B.Cu" "B.Mask" "B.Paste")
			(net "FM_BIOS_SPI_BMC_CTRL")
		)
		(pad "2" smd rect
			(at 0 0.889 270)
			(size 0.508 0.508)
			(layers "B.Cu" "B.Mask" "B.Paste")
			(net "GND")
		)
		(zone
			(layer "B.Cu")
			(hatch none 0.5)
			(connect_pads
				(clearance 0)
			)
			(min_thickness 0.25)
			(keepout
				(tracks allowed)
				(vias not_allowed)
				(pads allowed)
				(copperpour not_allowed)
				(footprints allowed)
			)
			(placement
				(enabled no)
				(sheetname "")
			)
			(fill
				(thermal_gap 0.5)
				(thermal_bridge_width 0.5)
				(island_removal_mode 0)
			)
			(polygon
				(pts
					(xy 385.5085 -54.864) (xy 385.5085 -54.356) (xy 385.8895 -54.356) (xy 385.8895 -54.864)
				)
			)
		)
		(zone
			(layer "B.Cu")
			(hatch none 0.5)
			(connect_pads
				(clearance 0)
			)
			(min_thickness 0.25)
			(keepout
				(tracks not_allowed)
				(vias allowed)
				(pads allowed)
				(copperpour not_allowed)
				(footprints allowed)
			)
			(placement
				(enabled no)
				(sheetname "")
			)
			(fill
				(thermal_gap 0.5)
				(thermal_bridge_width 0.5)
				(island_removal_mode 0)
			)
			(polygon
				(pts
					(xy 385.8895 -54.864) (xy 385.8895 -54.356) (xy 385.5085 -54.356) (xy 385.5085 -54.864)
				)
			)
		)
	)
	(footprint ""
		(layer "B.Cu")
		(at 197.848728 -89.187782 90)
		(property "Reference" "C6N11"
			(at 0 0 90)
			(layer "B.SilkS")
			(hide yes)
			(effects
				(font
					(size 1.27 1.27)
				)
				(justify mirror)
			)
		)
		(property "Value" ""
			(at 0 0 90)
			(layer "B.Fab")
			(effects
				(font
					(size 1.27 1.27)
				)
				(justify mirror)
			)
		)
		(duplicate_pad_numbers_are_jumpers no)
		(fp_rect
			(start -0.7239 -0.2159)
			(end 0.7239 1.9939)
			(stroke
				(width 0)
				(type default)
			)
			(fill no)
			(layer "B.CrtYd")
		)
		(fp_line
			(start 0.7239 -0.2159)
			(end 0.7239 1.9939)
			(stroke
				(width 0.1)
				(type default)
			)
			(layer "B.Fab")
		)
		(fp_line
			(start -0.7239 -0.2159)
			(end 0.7239 -0.2159)
			(stroke
				(width 0.1)
				(type default)
			)
			(layer "B.Fab")
		)
		(fp_line
			(start 0.7239 1.9939)
			(end -0.7239 1.9939)
			(stroke
				(width 0.1)
				(type default)
			)
			(layer "B.Fab")
		)
		(fp_line
			(start -0.7239 1.9939)
			(end -0.7239 -0.2159)
			(stroke
				(width 0.1)
				(type default)
			)
			(layer "B.Fab")
		)
		(pad "1" smd rect
			(at 0 0 270)
			(size 1.27 1.016)
			(layers "B.Cu" "B.Mask" "B.Paste")
			(net "VR_FET_SW_P12V_STBY_PVCCIN_CPU0")
		)
		(pad "2" smd rect
			(at 0 1.778 270)
			(size 1.27 1.016)
			(layers "B.Cu" "B.Mask" "B.Paste")
			(net "GND")
		)
		(zone
			(layer "B.Cu")
			(hatch none 0.5)
			(connect_pads
				(clearance 0)
			)
			(min_thickness 0.25)
			(keepout
				(tracks not_allowed)
				(vias allowed)
				(pads allowed)
				(copperpour not_allowed)
				(footprints allowed)
			)
			(placement
				(enabled no)
				(sheetname "")
			)
			(fill
				(thermal_gap 0.5)
				(thermal_bridge_width 0.5)
				(island_removal_mode 0)
			)
			(polygon
				(pts
					(xy 198.356728 -88.552782) (xy 199.118728 -88.552782) (xy 199.118728 -89.822782) (xy 198.356728 -89.822782)
				)
			)
		)
	)
	(footprint ""
		(layer "B.Cu")
		(at 179.197 -56.769 -90)
		(property "Reference" "R6R5"
			(at 0 0 90)
			(layer "B.SilkS")
			(hide yes)
			(effects
				(font
					(size 1.27 1.27)
				)
				(justify mirror)
			)
		)
		(property "Value" ""
			(at 0 0 90)
			(layer "B.Fab")
			(effects
				(font
					(size 1.27 1.27)
				)
				(justify mirror)
			)
		)
		(duplicate_pad_numbers_are_jumpers no)
		(fp_poly
			(pts
				(xy 0.2794 -0.1016) (xy -0.2794 -0.1016) (xy -0.2794 0.9906) (xy 0.2794 0.9906)
			)
			(stroke
				(width 0)
				(type default)
			)
			(fill no)
			(layer "B.CrtYd")
		)
		(fp_line
			(start -0.2794 0.9906)
			(end -0.2794 -0.1016)
			(stroke
				(width 0.1)
				(type default)
			)
			(layer "B.Fab")
		)
		(fp_line
			(start 0.2794 0.9906)
			(end -0.2794 0.9906)
			(stroke
				(width 0.1)
				(type default)
			)
			(layer "B.Fab")
		)
		(fp_line
			(start -0.2794 -0.1016)
			(end 0.2794 -0.1016)
			(stroke
				(width 0.1)
				(type default)
			)
			(layer "B.Fab")
		)
		(fp_line
			(start 0.2794 -0.1016)
			(end 0.2794 0.9906)
			(stroke
				(width 0.1)
				(type default)
			)
			(layer "B.Fab")
		)
		(pad "1" smd rect
			(at 0 0 90)
			(size 0.508 0.508)
			(layers "B.Cu" "B.Mask" "B.Paste")
			(net "VR_PVCCIO_CPU1_PH1_VCIN")
		)
		(pad "2" smd rect
			(at 0 0.889 90)
			(size 0.508 0.508)
			(layers "B.Cu" "B.Mask" "B.Paste")
			(net "P5V_STBY")
		)
		(zone
			(layer "B.Cu")
			(hatch none 0.5)
			(connect_pads
				(clearance 0)
			)
			(min_thickness 0.25)
			(keepout
				(tracks not_allowed)
				(vias allowed)
				(pads allowed)
				(copperpour not_allowed)
				(footprints allowed)
			)
			(placement
				(enabled no)
				(sheetname "")
			)
			(fill
				(thermal_gap 0.5)
				(thermal_bridge_width 0.5)
				(island_removal_mode 0)
			)
			(polygon
				(pts
					(xy 178.562 -56.515) (xy 178.562 -57.023) (xy 178.943 -57.023) (xy 178.943 -56.515)
				)
			)
		)
		(zone
			(layer "B.Cu")
			(hatch none 0.5)
			(connect_pads
				(clearance 0)
			)
			(min_thickness 0.25)
			(keepout
				(tracks allowed)
				(vias not_allowed)
				(pads allowed)
				(copperpour not_allowed)
				(footprints allowed)
			)
			(placement
				(enabled no)
				(sheetname "")
			)
			(fill
				(thermal_gap 0.5)
				(thermal_bridge_width 0.5)
				(island_removal_mode 0)
			)
			(polygon
				(pts
					(xy 178.943 -56.515) (xy 178.943 -57.023) (xy 178.562 -57.023) (xy 178.562 -56.515)
				)
			)
		)
	)
	(footprint ""
		(layer "B.Cu")
		(at 160.4264 -122.1994)
		(property "Reference" "R7M5"
			(at 0 0 0)
			(layer "B.SilkS")
			(hide yes)
			(effects
				(font
					(size 1.27 1.27)
				)
				(justify mirror)
			)
		)
		(property "Value" ""
			(at 0 0 0)
			(layer "B.Fab")
			(effects
				(font
					(size 1.27 1.27)
				)
				(justify mirror)
			)
		)
		(duplicate_pad_numbers_are_jumpers no)
		(fp_poly
			(pts
				(xy 0.2794 -0.1016) (xy -0.2794 -0.1016) (xy -0.2794 0.9906) (xy 0.2794 0.9906)
			)
			(stroke
				(width 0)
				(type default)
			)
			(fill no)
			(layer "B.CrtYd")
		)
		(fp_line
			(start -0.2794 -0.1016)
			(end 0.2794 -0.1016)
			(stroke
				(width 0.1)
				(type default)
			)
			(layer "B.Fab")
		)
		(fp_line
			(start -0.2794 0.9906)
			(end -0.2794 -0.1016)
			(stroke
				(width 0.1)
				(type default)
			)
			(layer "B.Fab")
		)
		(fp_line
			(start 0.2794 -0.1016)
			(end 0.2794 0.9906)
			(stroke
				(width 0.1)
				(type default)
			)
			(layer "B.Fab")
		)
		(fp_line
			(start 0.2794 0.9906)
			(end -0.2794 0.9906)
			(stroke
				(width 0.1)
				(type default)
			)
			(layer "B.Fab")
		)
		(pad "1" smd rect
			(at 0 0 180)
			(size 0.508 0.508)
			(layers "B.Cu" "B.Mask" "B.Paste")
			(net "SMB_DDR_KLM_VPP_SDA_R")
		)
		(pad "2" smd rect
			(at 0 0.889 180)
			(size 0.508 0.508)
			(layers "B.Cu" "B.Mask" "B.Paste")
			(net "SMB_DDR_KLM_VPP_SDA")
		)
		(zone
			(layer "B.Cu")
			(hatch none 0.5)
			(connect_pads
				(clearance 0)
			)
			(min_thickness 0.25)
			(keepout
				(tracks allowed)
				(vias not_allowed)
				(pads allowed)
				(copperpour not_allowed)
				(footprints allowed)
			)
			(placement
				(enabled no)
				(sheetname "")
			)
			(fill
				(thermal_gap 0.5)
				(thermal_bridge_width 0.5)
				(island_removal_mode 0)
			)
			(polygon
				(pts
					(xy 160.6804 -121.9454) (xy 160.1724 -121.9454) (xy 160.1724 -121.5644) (xy 160.6804 -121.5644)
				)
			)
		)
		(zone
			(layer "B.Cu")
			(hatch none 0.5)
			(connect_pads
				(clearance 0)
			)
			(min_thickness 0.25)
			(keepout
				(tracks not_allowed)
				(vias allowed)
				(pads allowed)
				(copperpour not_allowed)
				(footprints allowed)
			)
			(placement
				(enabled no)
				(sheetname "")
			)
			(fill
				(thermal_gap 0.5)
				(thermal_bridge_width 0.5)
				(island_removal_mode 0)
			)
			(polygon
				(pts
					(xy 160.6804 -121.5644) (xy 160.1724 -121.5644) (xy 160.1724 -121.9454) (xy 160.6804 -121.9454)
				)
			)
		)
	)
	(footprint ""
		(layer "B.Cu")
		(at 248.8565 -145.0086 -90)
		(property "Reference" "C5L12"
			(at -1.848866 0.752348 270)
			(unlocked yes)
			(layer "B.SilkS")
			(effects
				(font
					(size 1.27 0.9652)
					(thickness 0.1524)
				)
				(justify mirror)
			)
		)
		(property "Value" ""
			(at 0 0 90)
			(layer "B.Fab")
			(effects
				(font
					(size 1.27 1.27)
				)
				(justify mirror)
			)
		)
		(duplicate_pad_numbers_are_jumpers no)
		(fp_rect
			(start 0.500126 1.598422)
			(end -0.500126 -0.201422)
			(stroke
				(width 0)
				(type default)
			)
			(fill no)
			(layer "B.CrtYd")
		)
		(fp_line
			(start -0.500126 1.598422)
			(end 0.500126 1.598422)
			(stroke
				(width 0.1)
				(type default)
			)
			(layer "B.Fab")
		)
		(fp_line
			(start 0.500126 1.598422)
			(end 0.500126 -0.201422)
			(stroke
				(width 0.1)
				(type default)
			)
			(layer "B.Fab")
		)
		(fp_line
			(start -0.500126 -0.201422)
			(end -0.500126 1.598422)
			(stroke
				(width 0.1)
				(type default)
			)
			(layer "B.Fab")
		)
		(fp_line
			(start 0.500126 -0.201422)
			(end -0.500126 -0.201422)
			(stroke
				(width 0.1)
				(type default)
			)
			(layer "B.Fab")
		)
		(pad "1" smd rect
			(at 0 0 180)
			(size 0.889 0.9906)
			(layers "B.Cu" "B.Mask" "B.Paste")
			(net "PVDDQ_DEF")
		)
		(pad "2" smd rect
			(at 0 1.397 180)
			(size 0.889 0.9906)
			(layers "B.Cu" "B.Mask" "B.Paste")
			(net "GND")
		)
		(zone
			(layer "B.Cu")
			(hatch none 0.5)
			(connect_pads
				(clearance 0)
			)
			(min_thickness 0.25)
			(keepout
				(tracks not_allowed)
				(vias allowed)
				(pads allowed)
				(copperpour not_allowed)
				(footprints allowed)
			)
			(placement
				(enabled no)
				(sheetname "")
			)
			(fill
				(thermal_gap 0.5)
				(thermal_bridge_width 0.5)
				(island_removal_mode 0)
			)
			(polygon
				(pts
					(xy 247.904 -144.5133) (xy 248.412 -144.5133) (xy 248.412 -145.5039) (xy 247.904 -145.5039)
				)
			)
		)
		(zone
			(layer "B.Cu")
			(hatch none 0.5)
			(connect_pads
				(clearance 0)
			)
			(min_thickness 0.25)
			(keepout
				(tracks allowed)
				(vias not_allowed)
				(pads allowed)
				(copperpour not_allowed)
				(footprints allowed)
			)
			(placement
				(enabled no)
				(sheetname "")
			)
			(fill
				(thermal_gap 0.5)
				(thermal_bridge_width 0.5)
				(island_removal_mode 0)
			)
			(polygon
				(pts
					(xy 247.904 -144.5133) (xy 248.412 -144.5133) (xy 248.412 -145.5039) (xy 247.904 -145.5039)
				)
			)
		)
	)
	(footprint ""
		(layer "B.Cu")
		(at 359.8672 -4.2418 180)
		(property "Reference" "R8W10"
			(at 0.8382 -0.67818 180)
			(unlocked yes)
			(layer "B.SilkS")
			(effects
				(font
					(size 0.4064 0.254)
					(thickness 0.1524)
				)
				(justify left mirror)
			)
		)
		(property "Value" ""
			(at 0 0 0)
			(layer "B.Fab")
			(effects
				(font
					(size 1.27 1.27)
				)
				(justify mirror)
			)
		)
		(duplicate_pad_numbers_are_jumpers no)
		(fp_poly
			(pts
				(xy 0.2794 -0.1016) (xy -0.2794 -0.1016) (xy -0.2794 0.9906) (xy 0.2794 0.9906)
			)
			(stroke
				(width 0)
				(type default)
			)
			(fill no)
			(layer "B.CrtYd")
		)
		(fp_line
			(start 0.2794 0.9906)
			(end -0.2794 0.9906)
			(stroke
				(width 0.1)
				(type default)
			)
			(layer "B.Fab")
		)
		(fp_line
			(start 0.2794 -0.1016)
			(end 0.2794 0.9906)
			(stroke
				(width 0.1)
				(type default)
			)
			(layer "B.Fab")
		)
		(fp_line
			(start -0.2794 0.9906)
			(end -0.2794 -0.1016)
			(stroke
				(width 0.1)
				(type default)
			)
			(layer "B.Fab")
		)
		(fp_line
			(start -0.2794 -0.1016)
			(end 0.2794 -0.1016)
			(stroke
				(width 0.1)
				(type default)
			)
			(layer "B.Fab")
		)
		(pad "1" smd rect
			(at 0 0)
			(size 0.508 0.508)
			(layers "B.Cu" "B.Mask" "B.Paste")
			(net "JTAG_RISER_TMS")
		)
		(pad "2" smd rect
			(at 0 0.889)
			(size 0.508 0.508)
			(layers "B.Cu" "B.Mask" "B.Paste")
			(net "JTAG_PLD_TMS_MUX")
		)
		(zone
			(layer "B.Cu")
			(hatch none 0.5)
			(connect_pads
				(clearance 0)
			)
			(min_thickness 0.25)
			(keepout
				(tracks not_allowed)
				(vias allowed)
				(pads allowed)
				(copperpour not_allowed)
				(footprints allowed)
			)
			(placement
				(enabled no)
				(sheetname "")
			)
			(fill
				(thermal_gap 0.5)
				(thermal_bridge_width 0.5)
				(island_removal_mode 0)
			)
			(polygon
				(pts
					(xy 359.6132 -4.8768) (xy 360.1212 -4.8768) (xy 360.1212 -4.4958) (xy 359.6132 -4.4958)
				)
			)
		)
		(zone
			(layer "B.Cu")
			(hatch none 0.5)
			(connect_pads
				(clearance 0)
			)
			(min_thickness 0.25)
			(keepout
				(tracks allowed)
				(vias not_allowed)
				(pads allowed)
				(copperpour not_allowed)
				(footprints allowed)
			)
			(placement
				(enabled no)
				(sheetname "")
			)
			(fill
				(thermal_gap 0.5)
				(thermal_bridge_width 0.5)
				(island_removal_mode 0)
			)
			(polygon
				(pts
					(xy 359.6132 -4.4958) (xy 360.1212 -4.4958) (xy 360.1212 -4.8768) (xy 359.6132 -4.8768)
				)
			)
		)
	)
)
